# T6G (Grand Teton) — schematic netlist excerpt (pin names and nets, part order shuffled) for the footprints in the layout excerpt that follows; sources: Cadence DE-HDL packaged netlist, KiCad conversion of 04192023_DAF0TMB3IC0_F0TG_MB_C_brd_V02_OCP.brd

PC285  Q_CAP  22UF 4V 20% X6S  pkg C0805  page 209 : A = PVDD18_S5_P0 ; B = GND
C2654  Q_CAP  22UF 4V 20% X6S  pkg C0402  page 70 : A = PVDDIO_P0 ; B = GND
TP1  TP  NA  pkg TP  page 27 : TP = VSENSE_VSS_SENSE_A_P0

(kicad_pcb
	(version 20260206)
	(generator "pcbnew")
	(generator_version "10.0")
	(general
		(thickness 1.6)
		(legacy_teardrops no)
	)
	(paper "A4")
	(title_block
		(title "04192023_DAF0TMB3IC0_F0TG_MB_C_brd_V02_OCP.brd")
		(comment 1 "Grand Teton / footprints 7202-7204 of 8354")
	)
	(layers
		(0 "F.Cu" signal "TOP")
		(4 "In1.Cu" signal "GND")
		(6 "In2.Cu" signal "IN1")
		(8 "In3.Cu" signal "GND1")
		(10 "In4.Cu" signal "IN2")
		(12 "In5.Cu" signal "GND2")
		(14 "In6.Cu" signal "IN3")
		(16 "In7.Cu" signal "GND3")
		(18 "In8.Cu" signal "VCC")
		(20 "In9.Cu" signal "VCC1")
		(22 "In10.Cu" signal "GND4")
		(24 "In11.Cu" signal "IN4")
		(26 "In12.Cu" signal "GND5")
		(28 "In13.Cu" signal "IN5")
		(30 "In14.Cu" signal "GND6")
		(32 "In15.Cu" signal "IN6")
		(34 "In16.Cu" signal "GND7")
		(2 "B.Cu" signal "BOTTOM")
		(9 "F.Adhes" user "F.Adhesive")
		(11 "B.Adhes" user "B.Adhesive")
		(13 "F.Paste" user "Package Geometry/Pastemask Top")
		(15 "B.Paste" user "Package Geometry/Pastemask Bottom")
		(5 "F.SilkS" user "Ref Des/Silkscreen Top")
		(7 "B.SilkS" user "Ref Des/Silkscreen Bottom")
		(1 "F.Mask" user "Board Geometry/Soldermask Top")
		(3 "B.Mask" user "Board Geometry/Soldermask Bottom")
		(17 "Dwgs.User" user "User.Drawings")
		(19 "Cmts.User" user "User.Comments")
		(21 "Eco1.User" user "User.Eco1")
		(23 "Eco2.User" user "User.Eco2")
		(25 "Edge.Cuts" user "Board Geometry/Outline")
		(27 "Margin" user)
		(31 "F.CrtYd" user "Package Geometry/Place Bound Top")
		(29 "B.CrtYd" user "Package Geometry/Place Bound Bottom")
		(35 "F.Fab" user "Ref Des/Assembly Top")
		(33 "B.Fab" user "Ref Des/Assembly Bottom")
	)
	(footprint ""
		(layer "B.Cu")
		(at 333.561436 -151.069294 90)
		(property "Reference" "PC285"
			(at 0 0 90)
			(layer "B.SilkS")
			(hide yes)
			(effects
				(font
					(size 1.27 1.27)
				)
				(justify mirror)
			)
		)
		(property "Value" ""
			(at 0 0 90)
			(layer "B.Fab")
			(effects
				(font
					(size 1.27 1.27)
				)
				(justify mirror)
			)
		)
		(duplicate_pad_numbers_are_jumpers no)
		(fp_line
			(start 1.524 -0.762)
			(end -1.524 -0.762)
			(stroke
				(width 0.1524)
				(type default)
			)
			(layer "B.SilkS")
		)
		(fp_line
			(start -1.524 -0.762)
			(end -1.524 0.762)
			(stroke
				(width 0.1524)
				(type default)
			)
			(layer "B.SilkS")
		)
		(fp_line
			(start 1.524 0.762)
			(end 1.524 -0.762)
			(stroke
				(width 0.1524)
				(type default)
			)
			(layer "B.SilkS")
		)
		(fp_line
			(start -1.524 0.762)
			(end 1.524 0.762)
			(stroke
				(width 0.1524)
				(type default)
			)
			(layer "B.SilkS")
		)
		(fp_line
			(start 1.1049 -0.724916)
			(end 1.1049 0.724916)
			(stroke
				(width 0.1)
				(type default)
			)
			(layer "B.Fab")
		)
		(fp_line
			(start -1.1049 -0.724916)
			(end 1.1049 -0.724916)
			(stroke
				(width 0.1)
				(type default)
			)
			(layer "B.Fab")
		)
		(fp_line
			(start 1.1049 0.724916)
			(end -1.1049 0.724916)
			(stroke
				(width 0.1)
				(type default)
			)
			(layer "B.Fab")
		)
		(fp_line
			(start -1.1049 0.724916)
			(end -1.1049 -0.724916)
			(stroke
				(width 0.1)
				(type default)
			)
			(layer "B.Fab")
		)
		(pad "1" smd rect
			(at 0.889 0 90)
			(size 1.016 1.27)
			(layers "B.Cu" "B.Mask" "B.Paste")
			(net "PVDD18_S5_P0")
		)
		(pad "2" smd rect
			(at -0.889 0 90)
			(size 1.016 1.27)
			(layers "B.Cu" "B.Mask" "B.Paste")
			(net "GND")
		)
	)
	(footprint ""
		(layer "B.Cu")
		(at 421.974518 -175.029622)
		(property "Reference" "TP1"
			(at -0.72136 -1.224788 0)
			(unlocked yes)
			(layer "B.SilkS")
			(effects
				(font
					(size 0.7874 0.5842)
					(thickness 0.1524)
				)
				(justify left mirror)
			)
		)
		(property "Value" ""
			(at 0 0 0)
			(layer "B.Fab")
			(effects
				(font
					(size 1.27 1.27)
				)
				(justify mirror)
			)
		)
		(duplicate_pad_numbers_are_jumpers no)
		(pad "1" smd circle
			(at 0 0 180)
			(size 0.6604 0.6604)
			(layers "B.Cu" "B.Mask" "B.Paste")
			(net "VSENSE_VSS_SENSE_A_P0")
		)
	)
	(footprint ""
		(layer "B.Cu")
		(at 346.518992 -258.830064 180)
		(property "Reference" "C2654"
			(at 0 0 0)
			(layer "B.SilkS")
			(hide yes)
			(effects
				(font
					(size 1.27 1.27)
				)
				(justify mirror)
			)
		)
		(property "Value" ""
			(at 0 0 0)
			(layer "B.Fab")
			(effects
				(font
					(size 1.27 1.27)
				)
				(justify mirror)
			)
		)
		(duplicate_pad_numbers_are_jumpers no)
		(fp_line
			(start 0.7874 0.4064)
			(end 0.7874 -0.4064)
			(stroke
				(width 0.1524)
				(type default)
			)
			(layer "B.SilkS")
		)
		(fp_line
			(start 0.7874 -0.4064)
			(end -0.7874 -0.4064)
			(stroke
				(width 0.1524)
				(type default)
			)
			(layer "B.SilkS")
		)
		(fp_line
			(start -0.7874 0.4064)
			(end 0.7874 0.4064)
			(stroke
				(width 0.1524)
				(type default)
			)
			(layer "B.SilkS")
		)
		(fp_line
			(start -0.7874 -0.4064)
			(end -0.7874 0.4064)
			(stroke
				(width 0.1524)
				(type default)
			)
			(layer "B.SilkS")
		)
		(fp_line
			(start 0.67945 0.3048)
			(end 0.67945 -0.305054)
			(stroke
				(width 0.1)
				(type default)
			)
			(layer "B.Fab")
		)
		(fp_line
			(start 0.67945 -0.305054)
			(end 0.12065 -0.305054)
			(stroke
				(width 0.1)
				(type default)
			)
			(layer "B.Fab")
		)
		(fp_line
			(start 0.12065 0.3048)
			(end 0.67945 0.3048)
			(stroke
				(width 0.1)
				(type default)
			)
			(layer "B.Fab")
		)
		(fp_line
			(start 0.12065 0.2794)
			(end 0.12065 0.3048)
			(stroke
				(width 0.1)
				(type default)
			)
			(layer "B.Fab")
		)
		(fp_line
			(start 0.12065 -0.2794)
			(end -0.12065 -0.2794)
			(stroke
				(width 0.1)
				(type default)
			)
			(layer "B.Fab")
		)
		(fp_line
			(start 0.12065 -0.305054)
			(end 0.12065 -0.2794)
			(stroke
				(width 0.1)
				(type default)
			)
			(layer "B.Fab")
		)
		(fp_line
			(start -0.120396 0.3048)
			(end -0.120396 0.2794)
			(stroke
				(width 0.1)
				(type default)
			)
			(layer "B.Fab")
		)
		(fp_line
			(start -0.120396 0.2794)
			(end 0.12065 0.2794)
			(stroke
				(width 0.1)
				(type default)
			)
			(layer "B.Fab")
		)
		(fp_line
			(start -0.12065 -0.2794)
			(end -0.12065 -0.3048)
			(stroke
				(width 0.1)
				(type default)
			)
			(layer "B.Fab")
		)
		(fp_line
			(start -0.12065 -0.3048)
			(end -0.67945 -0.3048)
			(stroke
				(width 0.1)
				(type default)
			)
			(layer "B.Fab")
		)
		(fp_line
			(start -0.67945 0.3048)
			(end -0.120396 0.3048)
			(stroke
				(width 0.1)
				(type default)
			)
			(layer "B.Fab")
		)
		(fp_line
			(start -0.67945 -0.3048)
			(end -0.67945 0.3048)
			(stroke
				(width 0.1)
				(type default)
			)
			(layer "B.Fab")
		)
		(pad "1" smd circle
			(at 0.40005 0)
			(size 0 0)
			(layers "B.Cu" "B.Mask" "B.Paste")
			(net "PVDDIO_P0")
		)
		(pad "2" smd circle
			(at -0.40005 0)
			(size 0 0)
			(layers "B.Cu" "B.Mask" "B.Paste")
			(net "GND")
		)
	)
)
